G04 ================== begin FILE IDENTIFICATION RECORD ==================*
G04 Layout Name:  15750-1.brd*
G04 Film Name:    DP_REF_L3*
G04 File Format:  Gerber RS274X*
G04 File Origin:  Cadence Allegro 16.5-S056*
G04 Origin Date:  Fri Dec 30 13:21:43 2016*
G04 *
G04 Layer:  BOARD GEOMETRY/DP_REF_L3_TBL*
G04 Layer:  BOARD GEOMETRY/DP_REF_L3_L3*
G04 Layer:  BOARD GEOMETRY/PANEL_OUTLINE*
G04 *
G04 Offset:    (0.00 0.00)*
G04 Mirror:    No*
G04 Mode:      Positive*
G04 Rotation:  0*
G04 FullContactRelief:  No*
G04 UndefLineWidth:     6.00*
G04 ================== end FILE IDENTIFICATION RECORD ====================*
%FSLAX35Y35*MOIN*%
%IR0*IPPOS*OFA0.00000B0.00000*MIA0B0*SFA1.00000B1.00000*%
%ADD10C,.02*%
%ADD11C,.006*%
%ADD12C,.00525*%
G75*
%LPD*%
G75*
G54D10*
G01X772440Y279160D02*
X1577440D01*
G01X772440Y348460D02*
Y279160D01*
G01Y313810D02*
X1577440D01*
G01X772440Y348460D02*
X1577440D01*
G01X947440D02*
Y279160D01*
G01X1262440Y348460D02*
Y279160D01*
G01X1367440Y348460D02*
Y279160D01*
G01X1577440Y348460D02*
Y279160D01*
G54D11*
G01X6549Y-157539D02*
Y-175039D01*
G01X1527Y-157539D02*
X11571D01*
G01X20337Y-175039D02*
Y-157539D01*
G01Y-165997D02*
X21429Y-164539D01*
X22521Y-163664D01*
X24267Y-163373D01*
X25577Y-163664D01*
X27106Y-164831D01*
X27761Y-166581D01*
Y-175039D01*
G01X41549Y-163373D02*
Y-175039D01*
G01Y-158706D02*
X41112Y-158414D01*
Y-157831D01*
X41549Y-157539D01*
X41986Y-157831D01*
Y-158414D01*
X41549Y-158706D01*
G01X55774Y-172998D02*
X56866Y-174164D01*
X58394Y-175039D01*
X59704D01*
X61014Y-174456D01*
X61887Y-173581D01*
X62324Y-172415D01*
X62106Y-170664D01*
X61232Y-169789D01*
X57302Y-168039D01*
X56429Y-165997D01*
X56866Y-164539D01*
X57739Y-163664D01*
X59049Y-163373D01*
X60359Y-163664D01*
X61669Y-164539D01*
G01X90992Y-179414D02*
X92521Y-180581D01*
X94267Y-180872D01*
X95795Y-180581D01*
X97106Y-179123D01*
X97979Y-177081D01*
Y-163373D01*
G01Y-165706D02*
X97106Y-164539D01*
X95795Y-163664D01*
X94267Y-163373D01*
X92521Y-163956D01*
X91429Y-165122D01*
X90555Y-167164D01*
X90119Y-169206D01*
X90337Y-170956D01*
X91211Y-172998D01*
X92521Y-174456D01*
X94267Y-175039D01*
X95577Y-174747D01*
X97106Y-173581D01*
X97979Y-172415D01*
G01X108274Y-167164D02*
X115261D01*
X114606Y-165122D01*
X113514Y-163956D01*
X111986Y-163373D01*
X110457Y-163664D01*
X109147Y-164539D01*
X108274Y-166581D01*
X107837Y-168331D01*
Y-170081D01*
X108274Y-171831D01*
X109366Y-173581D01*
X110676Y-174747D01*
X112204Y-175039D01*
X113732Y-174456D01*
X115261Y-172706D01*
G01X125992Y-175039D02*
Y-163373D01*
G01Y-165706D02*
X127084Y-164539D01*
X128176Y-163664D01*
X129704Y-163373D01*
X130795Y-163664D01*
X132106Y-164539D01*
G01X142619Y-175039D02*
Y-157539D01*
G01Y-166289D02*
X143711Y-164539D01*
X145021Y-163664D01*
X146331Y-163373D01*
X148295Y-163956D01*
X149606Y-165122D01*
X150479Y-167164D01*
Y-169497D01*
X150042Y-171831D01*
X149169Y-173581D01*
X147641Y-174747D01*
X146331Y-175039D01*
X145021Y-174747D01*
X143711Y-173873D01*
X142619Y-172415D01*
G01X160774Y-167164D02*
X167761D01*
X167106Y-165122D01*
X166014Y-163956D01*
X164486Y-163373D01*
X162957Y-163664D01*
X161647Y-164539D01*
X160774Y-166581D01*
X160337Y-168331D01*
Y-170081D01*
X160774Y-171831D01*
X161866Y-173581D01*
X163176Y-174747D01*
X164704Y-175039D01*
X166232Y-174456D01*
X167761Y-172706D01*
G01X178492Y-175039D02*
Y-163373D01*
G01Y-165706D02*
X179584Y-164539D01*
X180676Y-163664D01*
X182204Y-163373D01*
X183295Y-163664D01*
X184606Y-164539D01*
G01X216549Y-163373D02*
Y-175039D01*
G01Y-158706D02*
X216112Y-158414D01*
Y-157831D01*
X216549Y-157539D01*
X216986Y-157831D01*
Y-158414D01*
X216549Y-158706D01*
G01X230774Y-172998D02*
X231866Y-174164D01*
X233394Y-175039D01*
X234704D01*
X236014Y-174456D01*
X236887Y-173581D01*
X237324Y-172415D01*
X237106Y-170664D01*
X236232Y-169789D01*
X232302Y-168039D01*
X231429Y-165997D01*
X231866Y-164539D01*
X232739Y-163664D01*
X234049Y-163373D01*
X235359Y-163664D01*
X236669Y-164539D01*
G01X265555Y-179414D02*
X267084Y-180581D01*
X268394Y-180872D01*
X270141Y-180289D01*
X271451Y-178831D01*
X272106Y-176205D01*
Y-163373D01*
G01Y-158706D02*
X271669Y-158414D01*
Y-157831D01*
X272106Y-157539D01*
X272542Y-157831D01*
Y-158414D01*
X272106Y-158706D01*
G01X282837Y-163373D02*
Y-171539D01*
X283711Y-173581D01*
X285021Y-174747D01*
X286549Y-175039D01*
X288077Y-174747D01*
X289387Y-173581D01*
X290261Y-171539D01*
G01Y-175039D02*
Y-163373D01*
G01X300774Y-172998D02*
X301866Y-174164D01*
X303394Y-175039D01*
X304704D01*
X306014Y-174456D01*
X306887Y-173581D01*
X307324Y-172415D01*
X307106Y-170664D01*
X306232Y-169789D01*
X302302Y-168039D01*
X301429Y-165997D01*
X301866Y-164539D01*
X302739Y-163664D01*
X304049Y-163373D01*
X305359Y-163664D01*
X306669Y-164539D01*
G01X321549Y-157539D02*
Y-175039D01*
G01X318492Y-163373D02*
X324606D01*
G01X355239Y-175039D02*
Y-160164D01*
X355676Y-158706D01*
X356549Y-157831D01*
X357859Y-157539D01*
X359169Y-158122D01*
X359824Y-159581D01*
G01X357204Y-164539D02*
X352837D01*
G01X374049Y-175039D02*
X372739Y-174747D01*
X371429Y-173581D01*
X370555Y-171539D01*
X370119Y-169206D01*
X370555Y-166872D01*
X371429Y-164831D01*
X372739Y-163664D01*
X374049Y-163373D01*
X375359Y-163664D01*
X376669Y-164831D01*
X377542Y-166872D01*
X377761Y-169206D01*
X377542Y-171539D01*
X376669Y-173581D01*
X375359Y-174747D01*
X374049Y-175039D01*
G01X388492D02*
Y-163373D01*
G01Y-165706D02*
X389584Y-164539D01*
X390676Y-163664D01*
X392204Y-163373D01*
X393295Y-163664D01*
X394606Y-164539D01*
G01X421964Y-180289D02*
X423274Y-180872D01*
X425021Y-180289D01*
X426112Y-179123D01*
X426986Y-177664D01*
X428295Y-172998D01*
X431134Y-163373D01*
G01X424147D02*
X428295Y-172998D01*
G01X444049Y-175039D02*
X442739Y-174747D01*
X441429Y-173581D01*
X440555Y-171539D01*
X440119Y-169206D01*
X440555Y-166872D01*
X441429Y-164831D01*
X442739Y-163664D01*
X444049Y-163373D01*
X445359Y-163664D01*
X446669Y-164831D01*
X447542Y-166872D01*
X447761Y-169206D01*
X447542Y-171539D01*
X446669Y-173581D01*
X445359Y-174747D01*
X444049Y-175039D01*
G01X457837Y-163373D02*
Y-171539D01*
X458711Y-173581D01*
X460021Y-174747D01*
X461549Y-175039D01*
X463077Y-174747D01*
X464387Y-173581D01*
X465261Y-171539D01*
G01Y-175039D02*
Y-163373D01*
G01X475992Y-175039D02*
Y-163373D01*
G01Y-165706D02*
X477084Y-164539D01*
X478176Y-163664D01*
X479704Y-163373D01*
X480795Y-163664D01*
X482106Y-164539D01*
G01X510992Y-175039D02*
Y-163373D01*
G01Y-165706D02*
X512084Y-164539D01*
X513176Y-163664D01*
X514704Y-163373D01*
X515795Y-163664D01*
X517106Y-164539D01*
G01X528274Y-167164D02*
X535261D01*
X534606Y-165122D01*
X533514Y-163956D01*
X531986Y-163373D01*
X530457Y-163664D01*
X529147Y-164539D01*
X528274Y-166581D01*
X527837Y-168331D01*
Y-170081D01*
X528274Y-171831D01*
X529366Y-173581D01*
X530676Y-174747D01*
X532204Y-175039D01*
X533732Y-174456D01*
X535261Y-172706D01*
G01X547739Y-175039D02*
Y-160164D01*
X548176Y-158706D01*
X549049Y-157831D01*
X550359Y-157539D01*
X551669Y-158122D01*
X552324Y-159581D01*
G01X549704Y-164539D02*
X545337D01*
G01X563274Y-167164D02*
X570261D01*
X569606Y-165122D01*
X568514Y-163956D01*
X566986Y-163373D01*
X565457Y-163664D01*
X564147Y-164539D01*
X563274Y-166581D01*
X562837Y-168331D01*
Y-170081D01*
X563274Y-171831D01*
X564366Y-173581D01*
X565676Y-174747D01*
X567204Y-175039D01*
X568732Y-174456D01*
X570261Y-172706D01*
G01X580992Y-175039D02*
Y-163373D01*
G01Y-165706D02*
X582084Y-164539D01*
X583176Y-163664D01*
X584704Y-163373D01*
X585795Y-163664D01*
X587106Y-164539D01*
G01X598274Y-167164D02*
X605261D01*
X604606Y-165122D01*
X603514Y-163956D01*
X601986Y-163373D01*
X600457Y-163664D01*
X599147Y-164539D01*
X598274Y-166581D01*
X597837Y-168331D01*
Y-170081D01*
X598274Y-171831D01*
X599366Y-173581D01*
X600676Y-174747D01*
X602204Y-175039D01*
X603732Y-174456D01*
X605261Y-172706D01*
G01X615337Y-175039D02*
Y-163373D01*
G01Y-166289D02*
X616211Y-164831D01*
X617521Y-163664D01*
X619267Y-163373D01*
X620795Y-163664D01*
X622106Y-164831D01*
X622761Y-166872D01*
Y-175039D01*
G01X640042Y-164831D02*
X638514Y-163664D01*
X637204Y-163373D01*
X635457Y-163956D01*
X634147Y-165122D01*
X633274Y-167164D01*
X633055Y-169206D01*
X633274Y-171248D01*
X634147Y-172998D01*
X635457Y-174456D01*
X637204Y-175039D01*
X638732Y-174456D01*
X640042Y-173289D01*
G01X650774Y-167164D02*
X657761D01*
X657106Y-165122D01*
X656014Y-163956D01*
X654486Y-163373D01*
X652957Y-163664D01*
X651647Y-164539D01*
X650774Y-166581D01*
X650337Y-168331D01*
Y-170081D01*
X650774Y-171831D01*
X651866Y-173581D01*
X653176Y-174747D01*
X654704Y-175039D01*
X656232Y-174456D01*
X657761Y-172706D01*
G01X689049Y-157539D02*
Y-175039D01*
G01X685992Y-163373D02*
X692106D01*
G01X706549Y-175039D02*
X705239Y-174747D01*
X703929Y-173581D01*
X703055Y-171539D01*
X702619Y-169206D01*
X703055Y-166872D01*
X703929Y-164831D01*
X705239Y-163664D01*
X706549Y-163373D01*
X707859Y-163664D01*
X709169Y-164831D01*
X710042Y-166872D01*
X710261Y-169206D01*
X710042Y-171539D01*
X709169Y-173581D01*
X707859Y-174747D01*
X706549Y-175039D01*
G01X740239D02*
Y-160164D01*
X740676Y-158706D01*
X741549Y-157831D01*
X742859Y-157539D01*
X744169Y-158122D01*
X744824Y-159581D01*
G01X742204Y-164539D02*
X737837D01*
G01X759049Y-163373D02*
Y-175039D01*
G01Y-158706D02*
X758612Y-158414D01*
Y-157831D01*
X759049Y-157539D01*
X759486Y-157831D01*
Y-158414D01*
X759049Y-158706D01*
G01X772837Y-175039D02*
Y-163373D01*
G01Y-166289D02*
X773711Y-164831D01*
X775021Y-163664D01*
X776767Y-163373D01*
X778295Y-163664D01*
X779606Y-164831D01*
X780261Y-166872D01*
Y-175039D01*
G01X797979Y-157539D02*
Y-175039D01*
G01Y-172415D02*
X797106Y-173873D01*
X795795Y-174747D01*
X794267Y-175039D01*
X792521Y-174456D01*
X791211Y-172998D01*
X790337Y-171248D01*
X790119Y-169206D01*
X790337Y-167164D01*
X791211Y-165414D01*
X792521Y-163956D01*
X794267Y-163373D01*
X795795Y-163664D01*
X796887Y-164248D01*
X797979Y-165414D01*
G01X829049Y-157539D02*
Y-175039D01*
G01X825992Y-163373D02*
X832106D01*
G01X842837Y-175039D02*
Y-157539D01*
G01Y-165997D02*
X843929Y-164539D01*
X845021Y-163664D01*
X846767Y-163373D01*
X848077Y-163664D01*
X849606Y-164831D01*
X850261Y-166581D01*
Y-175039D01*
G01X860774Y-167164D02*
X867761D01*
X867106Y-165122D01*
X866014Y-163956D01*
X864486Y-163373D01*
X862957Y-163664D01*
X861647Y-164539D01*
X860774Y-166581D01*
X860337Y-168331D01*
Y-170081D01*
X860774Y-171831D01*
X861866Y-173581D01*
X863176Y-174747D01*
X864704Y-175039D01*
X866232Y-174456D01*
X867761Y-172706D01*
G01X894246Y-175039D02*
Y-157539D01*
X898612D01*
X900359Y-158414D01*
X901669Y-159581D01*
X902761Y-161330D01*
X903634Y-163373D01*
X903852Y-166289D01*
X903634Y-169206D01*
X902761Y-171248D01*
X901669Y-172998D01*
X900359Y-174164D01*
X898612Y-175039D01*
X894246D01*
G01X912182D02*
Y-157539D01*
X917422D01*
X919169Y-158414D01*
X920479Y-160456D01*
X920916Y-162789D01*
X920479Y-165122D01*
X919387Y-166872D01*
X917422Y-167748D01*
X912182D01*
G01X951549Y-163373D02*
Y-175039D01*
G01Y-158706D02*
X951112Y-158414D01*
Y-157831D01*
X951549Y-157539D01*
X951986Y-157831D01*
Y-158414D01*
X951549Y-158706D01*
G01X962499Y-175039D02*
Y-163373D01*
G01Y-166581D02*
X963154Y-165122D01*
X964246Y-163956D01*
X965774Y-163373D01*
X967302Y-163956D01*
X968394Y-165122D01*
X969049Y-166581D01*
Y-175039D01*
G01Y-166581D02*
X969704Y-165122D01*
X970795Y-163956D01*
X972324Y-163373D01*
X973852Y-163956D01*
X974944Y-165122D01*
X975599Y-166872D01*
Y-175039D01*
G01X982619Y-180872D02*
Y-163373D01*
G01Y-165997D02*
X983711Y-164539D01*
X984802Y-163664D01*
X986549Y-163373D01*
X988077Y-163664D01*
X989606Y-165122D01*
X990261Y-167164D01*
X990479Y-169206D01*
X990261Y-171248D01*
X989606Y-173289D01*
X988295Y-174456D01*
X986549Y-175039D01*
X985021Y-174747D01*
X983492Y-173873D01*
X982619Y-172706D01*
G01X1000774Y-167164D02*
X1007761D01*
X1007106Y-165122D01*
X1006014Y-163956D01*
X1004486Y-163373D01*
X1002957Y-163664D01*
X1001647Y-164539D01*
X1000774Y-166581D01*
X1000337Y-168331D01*
Y-170081D01*
X1000774Y-171831D01*
X1001866Y-173581D01*
X1003176Y-174747D01*
X1004704Y-175039D01*
X1006232Y-174456D01*
X1007761Y-172706D01*
G01X1025479Y-157539D02*
Y-175039D01*
G01Y-172415D02*
X1024606Y-173873D01*
X1023295Y-174747D01*
X1021767Y-175039D01*
X1020021Y-174456D01*
X1018711Y-172998D01*
X1017837Y-171248D01*
X1017619Y-169206D01*
X1017837Y-167164D01*
X1018711Y-165414D01*
X1020021Y-163956D01*
X1021767Y-163373D01*
X1023295Y-163664D01*
X1024387Y-164248D01*
X1025479Y-165414D01*
G01X1042979Y-175039D02*
Y-163373D01*
G01Y-165414D02*
X1042106Y-164248D01*
X1040795Y-163664D01*
X1039267Y-163373D01*
X1037739Y-163956D01*
X1036429Y-165122D01*
X1035555Y-166872D01*
X1035119Y-169206D01*
X1035555Y-171539D01*
X1036429Y-173289D01*
X1037739Y-174456D01*
X1039267Y-175039D01*
X1040795Y-174747D01*
X1042106Y-173873D01*
X1042979Y-172706D01*
G01X1052837Y-175039D02*
Y-163373D01*
G01Y-166289D02*
X1053711Y-164831D01*
X1055021Y-163664D01*
X1056767Y-163373D01*
X1058295Y-163664D01*
X1059606Y-164831D01*
X1060261Y-166872D01*
Y-175039D01*
G01X1077542Y-164831D02*
X1076014Y-163664D01*
X1074704Y-163373D01*
X1072957Y-163956D01*
X1071647Y-165122D01*
X1070774Y-167164D01*
X1070555Y-169206D01*
X1070774Y-171248D01*
X1071647Y-172998D01*
X1072957Y-174456D01*
X1074704Y-175039D01*
X1076232Y-174456D01*
X1077542Y-173289D01*
G01X1088274Y-167164D02*
X1095261D01*
X1094606Y-165122D01*
X1093514Y-163956D01*
X1091986Y-163373D01*
X1090457Y-163664D01*
X1089147Y-164539D01*
X1088274Y-166581D01*
X1087837Y-168331D01*
Y-170081D01*
X1088274Y-171831D01*
X1089366Y-173581D01*
X1090676Y-174747D01*
X1092204Y-175039D01*
X1093732Y-174456D01*
X1095261Y-172706D01*
G01X1126549Y-157539D02*
Y-175039D01*
G01X1123492Y-163373D02*
X1129606D01*
G01X1140992Y-175039D02*
Y-163373D01*
G01Y-165706D02*
X1142084Y-164539D01*
X1143176Y-163664D01*
X1144704Y-163373D01*
X1145795Y-163664D01*
X1147106Y-164539D01*
G01X1165479Y-175039D02*
Y-163373D01*
G01Y-165414D02*
X1164606Y-164248D01*
X1163295Y-163664D01*
X1161767Y-163373D01*
X1160239Y-163956D01*
X1158929Y-165122D01*
X1158055Y-166872D01*
X1157619Y-169206D01*
X1158055Y-171539D01*
X1158929Y-173289D01*
X1160239Y-174456D01*
X1161767Y-175039D01*
X1163295Y-174747D01*
X1164606Y-173873D01*
X1165479Y-172706D01*
G01X1182542Y-164831D02*
X1181014Y-163664D01*
X1179704Y-163373D01*
X1177957Y-163956D01*
X1176647Y-165122D01*
X1175774Y-167164D01*
X1175555Y-169206D01*
X1175774Y-171248D01*
X1176647Y-172998D01*
X1177957Y-174456D01*
X1179704Y-175039D01*
X1181232Y-174456D01*
X1182542Y-173289D01*
G01X1193274Y-167164D02*
X1200261D01*
X1199606Y-165122D01*
X1198514Y-163956D01*
X1196986Y-163373D01*
X1195457Y-163664D01*
X1194147Y-164539D01*
X1193274Y-166581D01*
X1192837Y-168331D01*
Y-170081D01*
X1193274Y-171831D01*
X1194366Y-173581D01*
X1195676Y-174747D01*
X1197204Y-175039D01*
X1198732Y-174456D01*
X1200261Y-172706D01*
G01X1210774Y-172998D02*
X1211866Y-174164D01*
X1213394Y-175039D01*
X1214704D01*
X1216014Y-174456D01*
X1216887Y-173581D01*
X1217324Y-172415D01*
X1217106Y-170664D01*
X1216232Y-169789D01*
X1212302Y-168039D01*
X1211429Y-165997D01*
X1211866Y-164539D01*
X1212739Y-163664D01*
X1214049Y-163373D01*
X1215359Y-163664D01*
X1216669Y-164539D01*
G01X1249049Y-163373D02*
Y-175039D01*
G01Y-158706D02*
X1248612Y-158414D01*
Y-157831D01*
X1249049Y-157539D01*
X1249486Y-157831D01*
Y-158414D01*
X1249049Y-158706D01*
G01X1262837Y-175039D02*
Y-163373D01*
G01Y-166289D02*
X1263711Y-164831D01*
X1265021Y-163664D01*
X1266767Y-163373D01*
X1268295Y-163664D01*
X1269606Y-164831D01*
X1270261Y-166872D01*
Y-175039D01*
G01X1301549D02*
Y-157539D01*
G01X1322979Y-175039D02*
Y-163373D01*
G01Y-165414D02*
X1322106Y-164248D01*
X1320795Y-163664D01*
X1319267Y-163373D01*
X1317739Y-163956D01*
X1316429Y-165122D01*
X1315555Y-166872D01*
X1315119Y-169206D01*
X1315555Y-171539D01*
X1316429Y-173289D01*
X1317739Y-174456D01*
X1319267Y-175039D01*
X1320795Y-174747D01*
X1322106Y-173873D01*
X1322979Y-172706D01*
G01X1331964Y-180289D02*
X1333274Y-180872D01*
X1335021Y-180289D01*
X1336112Y-179123D01*
X1336986Y-177664D01*
X1338295Y-172998D01*
X1341134Y-163373D01*
G01X1334147D02*
X1338295Y-172998D01*
G01X1350774Y-167164D02*
X1357761D01*
X1357106Y-165122D01*
X1356014Y-163956D01*
X1354486Y-163373D01*
X1352957Y-163664D01*
X1351647Y-164539D01*
X1350774Y-166581D01*
X1350337Y-168331D01*
Y-170081D01*
X1350774Y-171831D01*
X1351866Y-173581D01*
X1353176Y-174747D01*
X1354704Y-175039D01*
X1356232Y-174456D01*
X1357761Y-172706D01*
G01X1368492Y-175039D02*
Y-163373D01*
G01Y-165706D02*
X1369584Y-164539D01*
X1370676Y-163664D01*
X1372204Y-163373D01*
X1373295Y-163664D01*
X1374606Y-164539D01*
G01X1402182Y-157539D02*
Y-175039D01*
X1410916D01*
G01X1419246Y-171539D02*
X1420555Y-173581D01*
X1422302Y-174747D01*
X1424267Y-175039D01*
X1426014Y-174747D01*
X1427761Y-173289D01*
X1428852Y-171539D01*
X1429071Y-169789D01*
X1428634Y-167748D01*
X1427106Y-166289D01*
X1425577Y-165706D01*
X1423612D01*
G01X1425577D02*
X1426887Y-164831D01*
X1427979Y-163373D01*
X1428416Y-161623D01*
X1427979Y-159872D01*
X1426887Y-158414D01*
X1424922Y-157539D01*
X1422957Y-157831D01*
X1420992Y-158998D01*
G01X1441549Y-175622D02*
X1441112Y-175331D01*
Y-174747D01*
X1441549Y-174456D01*
X1441986Y-174747D01*
Y-175331D01*
X1441549Y-175622D01*
G01X-1Y-113228D02*
Y-117165D01*
G03X7873Y-125039I7874J0D01*
G01X714566D01*
G03X722440Y-117165I0J7874D01*
G01Y-113228D01*
G01X1968Y40473D02*
X9842D01*
G02X11811Y38504I0J-1969D01*
G01Y-16772D01*
G02X9842Y-18740I-1969J1D01*
G01X1968D01*
G03X0Y-20709I0J-1968D01*
G01Y-97480D01*
G03X7874Y-105354I7874J0D01*
G01X341535D01*
G03X349409Y-97480I0J7874D01*
G01Y-15748D01*
G03X341535Y-7874I-7874J0D01*
G01X141338D01*
G02X133464Y0I0J7874D01*
G01Y250197D01*
G03X125590Y258071I-7874J0D01*
G01X1968D01*
G03X0Y256102I0J-1968D01*
G01Y236673D01*
G03X1968Y234705I1968J0D01*
G01X28346D01*
G02X30315Y232736I0J-1969D01*
G01Y216004D01*
G02X28346Y214036I-1968J0D01*
G01X23228D01*
G03X21259Y212067I0J-1969D01*
G01Y86752D01*
G03X23228Y84784I1969J1D01*
G01X28346D01*
G02X30315Y82815I0J-1969D01*
G01Y66083D01*
G02X28346Y64114I-1969J0D01*
G01X1968D01*
G03X0Y62146I0J-1968D01*
G01Y42441D01*
G03X1968Y40473I1968J0D01*
G01X-1Y-113228D02*
X13591D01*
G01X347441Y217598D02*
X339567D01*
G02X337598Y219567I0J1969D01*
G01Y274843D01*
G02X339567Y276811I1969J-1D01*
G01X347441D01*
G03X349409Y278780I0J1968D01*
G01Y355551D01*
G03X341535Y363425I-7874J0D01*
G01X7874D01*
G03X0Y355551I0J-7874D01*
G01Y273819D01*
G03X7874Y265945I7874J0D01*
G01X208071D01*
G02X215945Y258071I0J-7874D01*
G01Y7874D01*
G03X223819Y0I7874J0D01*
G01X347441D01*
G03X349409Y1969I0J1968D01*
G01Y21398D01*
G03X347441Y23366I-1968J0D01*
G01X321063D01*
G02X319094Y25335I0J1969D01*
G01Y42067D01*
G02X321063Y44035I1969J-1D01*
G01X326181D01*
G03X328150Y46004I0J1969D01*
G01Y171319D01*
G03X326181Y173287I-1968J0D01*
G01X321063D01*
G02X319094Y175256I0J1969D01*
G01Y191988D01*
G02X321063Y193957I1969J0D01*
G01X347441D01*
G03X349409Y195925I0J1968D01*
G01Y215630D01*
G03X347441Y217598I-1968J0D01*
G01X245745Y383110D02*
X7874D01*
G03X0Y375236I0J-7874D01*
G01Y371299D01*
G01D02*
X13591D01*
G01Y-113228D02*
G03Y-105354I0J3937D01*
G01Y258071D02*
G03Y265945I0J3937D01*
G01Y363425D02*
G03Y371299I0J3937D01*
G01X38787Y-113228D02*
X237000D01*
G01X38787Y-105354D02*
G03Y-113228I1J-3937D01*
G01Y265945D02*
G03Y258071I1J-3937D01*
G01X237000Y371299D02*
X38787D01*
G01D02*
G03Y363425I1J-3937D01*
G01X141338Y116437D02*
G03X133464I-3937J0D01*
G01Y141634D02*
G03X141338I3937J0D01*
G01Y0D02*
Y116437D01*
G01X162106Y0D02*
X141337D01*
G01X141338Y141634D02*
Y258071D01*
G01D02*
X162106D01*
G01Y-7874D02*
G03Y0I0J3937D01*
G01X179626Y62719D02*
G03X171044I-4291J0D01*
G03X179626I4291J0D01*
G01Y189063D02*
G03X171044Y189062I-4291J0D01*
G03X179626Y189063I4291J1D01*
G01X162106Y258071D02*
G03Y265945I0J3937D01*
G01X187302Y0D02*
G03Y-7874I1J-3937D01*
G01X208071Y0D02*
X187302D01*
G01Y265945D02*
G03Y258071I1J-3937D01*
G01D02*
X208071D01*
G01X207913Y0D02*
X208071D01*
G01Y116437D02*
Y0D01*
G01X215945Y116437D02*
G03X208071I-3937J0D01*
G01Y141634D02*
G03X215945I3937J0D01*
G01X208071Y258071D02*
Y141634D01*
G01X237000Y-113228D02*
G03Y-105354I0J3937D01*
G01Y363425D02*
G03Y371299I0J3937D01*
G01X245745Y383110D02*
G03X253619I3937J0D01*
G01X722440Y371299D02*
Y375236D01*
G03X714566Y383110I-7874J0D01*
G01X253619D01*
G01X262196Y-113228D02*
X460244D01*
G01X262196Y-105354D02*
G03Y-113228I0J-3937D01*
G01Y371299D02*
X460244D01*
G01X262196D02*
G03Y363425I0J-3937D01*
G01X310621Y-7874D02*
G03Y0I0J3937D01*
G01X335817D02*
G03Y-7874I1J-3937D01*
G01X353346Y-47481D02*
G03X349409Y-51418I0J-3937D01*
G01Y-20709D02*
G03X353346Y-24646I3937J0D01*
G01Y282717D02*
G03X349409Y278780I0J-3937D01*
G01Y309489D02*
G03X353346Y305552I3937J0D01*
G01Y-47481D02*
X369094D01*
G01X373031Y-51418D02*
G03X369094Y-47481I-3937J0D01*
G01X353346Y-24646D02*
X369094D01*
G01D02*
G03X373031Y-20709I0J3937D01*
G01X353346Y282717D02*
X369094D01*
G01X373031Y278780D02*
G03X369094Y282717I-3937J0D01*
G01X353346Y305552D02*
X369094D01*
G01D02*
G03X373031Y309489I0J3937D01*
G01X374999Y40473D02*
X382873D01*
G02X384842Y38504I0J-1969D01*
G01Y-16772D01*
G02X382873Y-18740I-1969J1D01*
G01X374999D01*
G03X373031Y-20709I0J-1968D01*
G01Y-97480D01*
G03X380905Y-105354I7874J0D01*
G01X714566D01*
G03X722440Y-97480I0J7874D01*
G01Y-15748D01*
G03X714566Y-7874I-7874J0D01*
G01X514369D01*
G02X506495Y0I0J7874D01*
G01Y250197D01*
G03X498621Y258071I-7874J0D01*
G01X374999D01*
G03X373031Y256102I0J-1968D01*
G01Y236673D01*
G03X374999Y234705I1968J0D01*
G01X401377D01*
G02X403346Y232736I0J-1969D01*
G01Y216004D01*
G02X401377Y214036I-1968J0D01*
G01X396259D01*
G03X394290Y212067I0J-1969D01*
G01Y86752D01*
G03X396259Y84784I1969J1D01*
G01X401377D01*
G02X403346Y82815I0J-1969D01*
G01Y66083D01*
G02X401377Y64114I-1969J0D01*
G01X374999D01*
G03X373031Y62146I0J-1968D01*
G01Y42441D01*
G03X374999Y40473I1968J0D01*
G01X720472Y217598D02*
X712598D01*
G02X710629Y219567I0J1969D01*
G01Y274843D01*
G02X712598Y276811I1969J-1D01*
G01X720472D01*
G03X722440Y278780I0J1968D01*
G01Y355551D01*
G03X714566Y363425I-7874J0D01*
G01X380905D01*
G03X373031Y355551I0J-7874D01*
G01Y273819D01*
G03X380905Y265945I7874J0D01*
G01X581102D01*
G02X588976Y258071I0J-7874D01*
G01Y7874D01*
G03X596850Y0I7874J0D01*
G01X720472D01*
G03X722440Y1969I0J1968D01*
G01Y21398D01*
G03X720472Y23366I-1968J0D01*
G01X694094D01*
G02X692125Y25335I0J1969D01*
G01Y42067D01*
G02X694094Y44035I1969J-1D01*
G01X699212D01*
G03X701181Y46004I0J1969D01*
G01Y171319D01*
G03X699212Y173287I-1969J-1D01*
G01X694094D01*
G02X692125Y175256I0J1969D01*
G01Y191988D01*
G02X694094Y193957I1969J0D01*
G01X720472D01*
G03X722440Y195925I0J1968D01*
G01Y215630D01*
G03X720472Y217598I-1968J0D01*
G01X386622Y258071D02*
G03Y265945I0J3937D01*
G01X411819D02*
G03Y258071I0J-3937D01*
G01X460244Y-113228D02*
G03Y-105354I0J3937D01*
G01Y363425D02*
G03Y371299I0J3937D01*
G01X485441Y-105354D02*
G03Y-113228I0J-3937D01*
G01Y371299D02*
G03Y363425I0J-3937D01*
G01Y-113228D02*
X683652D01*
G01X485441Y371299D02*
X683652D01*
G01X514369Y0D02*
Y116437D01*
G01X535137Y0D02*
X514369D01*
G01Y116437D02*
G03X506494I-3937J0D01*
G01Y141634D02*
G03X514369I3937J0D01*
G01D02*
Y258071D01*
G01D02*
X535137D01*
G01Y-7874D02*
G03Y0I0J3937D01*
G01X551396Y69008D02*
G03X542813I-4291J0D01*
G03X551396I4291J0D01*
G01Y195351D02*
G03X542813Y195352I-4292J0D01*
G03X551396Y195351I4291J-1D01*
G01X535137Y258071D02*
G03Y265945I0J3937D01*
G01X560333Y0D02*
G03Y-7874I1J-3937D01*
G01X581102Y0D02*
X560333D01*
G01Y265945D02*
G03Y258071I1J-3937D01*
G01D02*
X581102D01*
G01Y116437D02*
Y0D01*
G01X588976Y116437D02*
G03X581102I-3937J0D01*
G01Y141634D02*
G03X588976I3937J0D01*
G01X581102Y258071D02*
Y141634D01*
G01X683652Y-113228D02*
G03Y-105354I0J3937D01*
G01Y-7874D02*
G03Y0I0J3937D01*
G01Y363425D02*
G03Y371299I0J3937D01*
G01X708848Y-113228D02*
X722440D01*
G01X708848Y-105354D02*
G03Y-113228I1J-3937D01*
G01Y0D02*
G03Y-7874I1J-3937D01*
G01Y371299D02*
X722440D01*
G01X708848D02*
G03Y363425I1J-3937D01*
G01X774187Y358210D02*
Y375710D01*
X778553D01*
X780300Y374835D01*
X781610Y373668D01*
X782702Y371919D01*
X783575Y369876D01*
X783793Y366960D01*
X783575Y364043D01*
X782702Y362001D01*
X781610Y360251D01*
X780300Y359085D01*
X778553Y358210D01*
X774187D01*
G01X792123D02*
Y375710D01*
X797363D01*
X799110Y374835D01*
X800420Y372793D01*
X800857Y370460D01*
X800420Y368127D01*
X799328Y366377D01*
X797363Y365501D01*
X792123D01*
G01X828870Y375710D02*
X834110D01*
G01X831490D02*
Y358210D01*
G01X828870D02*
X834110D01*
G01X843313D02*
Y375710D01*
X848990Y361127D01*
X854667Y375710D01*
Y358210D01*
G01X862123D02*
Y375710D01*
X867363D01*
X869110Y374835D01*
X870420Y372793D01*
X870857Y370460D01*
X870420Y368127D01*
X869328Y366377D01*
X867363Y365501D01*
X862123D01*
G01X888357Y358210D02*
X879623D01*
Y375710D01*
X888357D01*
G01X884863Y367252D02*
X879623D01*
G01X896687Y358210D02*
Y375710D01*
X901053D01*
X902800Y374835D01*
X904110Y373668D01*
X905202Y371919D01*
X906075Y369876D01*
X906293Y366960D01*
X906075Y364043D01*
X905202Y362001D01*
X904110Y360251D01*
X902800Y359085D01*
X901053Y358210D01*
X896687D01*
G01X913531D02*
X918990Y375710D01*
X924449Y358210D01*
G01X922483Y364335D02*
X915496D01*
G01X931468Y358210D02*
Y375710D01*
X941512Y358210D01*
Y375710D01*
G01X958793Y374251D02*
X957483Y375127D01*
X955955Y375710D01*
X954208D01*
X952243Y374835D01*
X950715Y373377D01*
X949623Y371626D01*
X948750Y368710D01*
X948531Y366085D01*
X948968Y363460D01*
X949623Y361710D01*
X950933Y359960D01*
X952462Y358793D01*
X953990Y358210D01*
X955518D01*
X957047Y358793D01*
X958357Y359668D01*
X959449Y360834D01*
G01X975857Y358210D02*
X967123D01*
Y375710D01*
X975857D01*
G01X972363Y367252D02*
X967123D01*
G01X1006490Y375710D02*
Y358210D01*
G01X1001468Y375710D02*
X1011512D01*
G01X1018531Y358210D02*
X1023990Y375710D01*
X1029449Y358210D01*
G01X1027483Y364335D02*
X1020496D01*
G01X1043236Y367543D02*
X1044110Y368418D01*
X1044765Y369876D01*
X1045202Y371919D01*
X1044765Y373668D01*
X1043892Y374835D01*
X1042363Y375710D01*
X1036468D01*
Y358210D01*
X1043673D01*
X1045202Y359376D01*
X1046075Y361127D01*
X1046512Y363168D01*
X1046075Y365210D01*
X1044765Y366960D01*
X1043236Y367543D01*
X1036468D01*
G01X1054623Y375710D02*
Y358210D01*
X1063357D01*
G01X1080857D02*
X1072123D01*
Y375710D01*
X1080857D01*
G01X1077363Y367252D02*
X1072123D01*
G01X1093990Y357627D02*
X1093553Y357918D01*
Y358502D01*
X1093990Y358793D01*
X1094427Y358502D01*
Y357918D01*
X1093990Y357627D01*
G01Y365501D02*
X1093553Y365793D01*
Y366377D01*
X1093990Y366668D01*
X1094427Y366377D01*
Y365793D01*
X1093990Y365501D01*
G01X1124623Y375710D02*
Y358210D01*
X1133357D01*
G01X1141687Y361710D02*
X1142996Y359668D01*
X1144743Y358502D01*
X1146708Y358210D01*
X1148455Y358502D01*
X1150202Y359960D01*
X1151293Y361710D01*
X1151512Y363460D01*
X1151075Y365501D01*
X1149547Y366960D01*
X1148018Y367543D01*
X1146053D01*
G01X1148018D02*
X1149328Y368418D01*
X1150420Y369876D01*
X1150857Y371626D01*
X1150420Y373377D01*
X1149328Y374835D01*
X1147363Y375710D01*
X1145398Y375418D01*
X1143433Y374251D01*
G01X796070Y341060D02*
X801310D01*
G01X798690D02*
Y323560D01*
G01X796070D02*
X801310D01*
G01X810513D02*
Y341060D01*
X816190Y326477D01*
X821867Y341060D01*
Y323560D01*
G01X829323D02*
Y341060D01*
X834563D01*
X836310Y340185D01*
X837620Y338143D01*
X838057Y335810D01*
X837620Y333477D01*
X836528Y331727D01*
X834563Y330851D01*
X829323D01*
G01X850098Y317727D02*
X847915Y320643D01*
X846823Y323560D01*
Y335226D01*
X847915Y338143D01*
X850098Y341060D01*
G01X868690Y323560D02*
X866943Y323852D01*
X865415Y325018D01*
X864105Y326768D01*
X863231Y328810D01*
X862795Y331143D01*
Y333477D01*
X863231Y335810D01*
X864105Y337852D01*
X865415Y339601D01*
X866943Y340768D01*
X868690Y341060D01*
X870436Y340768D01*
X871965Y339601D01*
X873275Y337852D01*
X874149Y335810D01*
X874585Y333477D01*
Y331143D01*
X874149Y328810D01*
X873275Y326768D01*
X871965Y325018D01*
X870436Y323852D01*
X868690Y323560D01*
G01X882478D02*
Y341060D01*
G01Y332602D02*
X883570Y334060D01*
X884662Y334935D01*
X886408Y335226D01*
X887718Y334935D01*
X889247Y333768D01*
X889902Y332018D01*
Y323560D01*
G01X897140D02*
Y335226D01*
G01Y332018D02*
X897795Y333477D01*
X898887Y334643D01*
X900415Y335226D01*
X901943Y334643D01*
X903035Y333477D01*
X903690Y332018D01*
Y323560D01*
G01Y332018D02*
X904345Y333477D01*
X905436Y334643D01*
X906965Y335226D01*
X908493Y334643D01*
X909585Y333477D01*
X910240Y331727D01*
Y323560D01*
G01X922282Y317727D02*
X924465Y320643D01*
X925557Y323560D01*
Y335226D01*
X924465Y338143D01*
X922282Y341060D01*
G01X833690Y288910D02*
X835218Y289202D01*
X836965Y290076D01*
X838057Y291534D01*
X838493Y293577D01*
X838057Y295618D01*
X836747Y297368D01*
X834782Y298243D01*
X832598D01*
X831288Y298827D01*
X830196Y300285D01*
X829760Y302326D01*
X830415Y304368D01*
X831943Y305827D01*
X833690Y306410D01*
X835436Y305827D01*
X836965Y304368D01*
X837620Y302326D01*
X837183Y300285D01*
X836092Y298827D01*
X834782Y298243D01*
X832598D01*
X830633Y297368D01*
X829323Y295618D01*
X828887Y293577D01*
X829323Y291534D01*
X830415Y290076D01*
X832162Y289202D01*
X833690Y288910D01*
G01X846387Y291534D02*
X847696Y290076D01*
X849225Y289202D01*
X851190Y288910D01*
X853155Y289493D01*
X854683Y290660D01*
X855775Y292701D01*
X855993Y295035D01*
X855557Y297368D01*
X854465Y298827D01*
X852936Y299993D01*
X851408Y300285D01*
X849880Y299993D01*
X847915Y298827D01*
X848570Y306410D01*
X854465D01*
G01X868690Y288327D02*
X868253Y288618D01*
Y289202D01*
X868690Y289493D01*
X869127Y289202D01*
Y288618D01*
X868690Y288327D01*
G01X886190Y306410D02*
X884443Y305827D01*
X883133Y304368D01*
X882260Y302619D01*
X881605Y300285D01*
X881387Y297660D01*
X881605Y295035D01*
X882260Y292701D01*
X883133Y290951D01*
X884443Y289493D01*
X886190Y288910D01*
X887936Y289493D01*
X889247Y290951D01*
X890120Y292701D01*
X890775Y295035D01*
X890993Y297660D01*
X890775Y300285D01*
X890120Y302619D01*
X889247Y304368D01*
X887936Y305827D01*
X886190Y306410D01*
G01X1010890Y341060D02*
X1013946Y323560D01*
X1017440Y341060D01*
X1020933Y323560D01*
X1023990Y341060D01*
G01X1032320D02*
X1037560D01*
G01X1034940D02*
Y323560D01*
G01X1032320D02*
X1037560D01*
G01X1047637D02*
Y341060D01*
X1052003D01*
X1053750Y340185D01*
X1055060Y339018D01*
X1056152Y337269D01*
X1057025Y335226D01*
X1057243Y332310D01*
X1057025Y329393D01*
X1056152Y327351D01*
X1055060Y325601D01*
X1053750Y324435D01*
X1052003Y323560D01*
X1047637D01*
G01X1069940Y341060D02*
Y323560D01*
G01X1064918Y341060D02*
X1074962D01*
G01X1082855Y323560D02*
Y341060D01*
G01X1092025D02*
Y323560D01*
G01Y332310D02*
X1082855D01*
G01X1103848Y317727D02*
X1101665Y320643D01*
X1100573Y323560D01*
Y335226D01*
X1101665Y338143D01*
X1103848Y341060D01*
G01X1115890Y323560D02*
Y335226D01*
G01Y332018D02*
X1116545Y333477D01*
X1117637Y334643D01*
X1119165Y335226D01*
X1120693Y334643D01*
X1121785Y333477D01*
X1122440Y332018D01*
Y323560D01*
G01Y332018D02*
X1123095Y333477D01*
X1124186Y334643D01*
X1125715Y335226D01*
X1127243Y334643D01*
X1128335Y333477D01*
X1128990Y331727D01*
Y323560D01*
G01X1139940Y335226D02*
Y323560D01*
G01Y339893D02*
X1139503Y340185D01*
Y340768D01*
X1139940Y341060D01*
X1140377Y340768D01*
Y340185D01*
X1139940Y339893D01*
G01X1157440Y323560D02*
Y341060D01*
G01X1171665Y325601D02*
X1172757Y324435D01*
X1174285Y323560D01*
X1175595D01*
X1176905Y324143D01*
X1177778Y325018D01*
X1178215Y326184D01*
X1177997Y327935D01*
X1177123Y328810D01*
X1173193Y330560D01*
X1172320Y332602D01*
X1172757Y334060D01*
X1173630Y334935D01*
X1174940Y335226D01*
X1176250Y334935D01*
X1177560Y334060D01*
G01X1193532Y317727D02*
X1195715Y320643D01*
X1196807Y323560D01*
Y335226D01*
X1195715Y338143D01*
X1193532Y341060D01*
G01X1038887Y291534D02*
X1040196Y290076D01*
X1041725Y289202D01*
X1043690Y288910D01*
X1045655Y289493D01*
X1047183Y290660D01*
X1048275Y292701D01*
X1048493Y295035D01*
X1048057Y297368D01*
X1046965Y298827D01*
X1045436Y299993D01*
X1043908Y300285D01*
X1042380Y299993D01*
X1040415Y298827D01*
X1041070Y306410D01*
X1046965D01*
G01X1061190Y288327D02*
X1060753Y288618D01*
Y289202D01*
X1061190Y289493D01*
X1061627Y289202D01*
Y288618D01*
X1061190Y288327D01*
G01X1074542Y303493D02*
X1075852Y305243D01*
X1077380Y306118D01*
X1079127Y306410D01*
X1081310Y305827D01*
X1082838Y304368D01*
X1083275Y302619D01*
X1083057Y300868D01*
X1082183Y299410D01*
X1077817Y296493D01*
X1075852Y294452D01*
X1074542Y291534D01*
X1074105Y288910D01*
X1083275D01*
G01X1091387Y291534D02*
X1092696Y290076D01*
X1094225Y289202D01*
X1096190Y288910D01*
X1098155Y289493D01*
X1099683Y290660D01*
X1100775Y292701D01*
X1100993Y295035D01*
X1100557Y297368D01*
X1099465Y298827D01*
X1097936Y299993D01*
X1096408Y300285D01*
X1094880Y299993D01*
X1092915Y298827D01*
X1093570Y306410D01*
X1099465D01*
G01X1109760Y288327D02*
X1117620Y306410D01*
G01X1130753Y288910D02*
X1131190Y292701D01*
X1131845Y295910D01*
X1132718Y298827D01*
X1133810Y302035D01*
X1135557Y306410D01*
X1126823D01*
G01X1148690Y288327D02*
X1148253Y288618D01*
Y289202D01*
X1148690Y289493D01*
X1149127Y289202D01*
Y288618D01*
X1148690Y288327D01*
G01X1161387Y291534D02*
X1162696Y290076D01*
X1164225Y289202D01*
X1166190Y288910D01*
X1168155Y289493D01*
X1169683Y290660D01*
X1170775Y292701D01*
X1170993Y295035D01*
X1170557Y297368D01*
X1169465Y298827D01*
X1167936Y299993D01*
X1166408Y300285D01*
X1164880Y299993D01*
X1162915Y298827D01*
X1163570Y306410D01*
X1169465D01*
G01X1288690Y341060D02*
Y323560D01*
G01X1283668Y341060D02*
X1293712D01*
G01X1306190Y323560D02*
Y331435D01*
X1301823Y341060D01*
G01X1310557D02*
X1306190Y331435D01*
G01X1319323Y323560D02*
Y341060D01*
X1324563D01*
X1326310Y340185D01*
X1327620Y338143D01*
X1328057Y335810D01*
X1327620Y333477D01*
X1326528Y331727D01*
X1324563Y330851D01*
X1319323D01*
G01X1345557Y323560D02*
X1336823D01*
Y341060D01*
X1345557D01*
G01X1342063Y332602D02*
X1336823D01*
G01X1301387Y288910D02*
Y306410D01*
X1305753D01*
X1307500Y305535D01*
X1308810Y304368D01*
X1309902Y302619D01*
X1310775Y300576D01*
X1310993Y297660D01*
X1310775Y294743D01*
X1309902Y292701D01*
X1308810Y290951D01*
X1307500Y289785D01*
X1305753Y288910D01*
X1301387D01*
G01X1319323D02*
Y306410D01*
X1324563D01*
X1326310Y305535D01*
X1327620Y303493D01*
X1328057Y301160D01*
X1327620Y298827D01*
X1326528Y297077D01*
X1324563Y296201D01*
X1319323D01*
G01X1389323Y323560D02*
Y341060D01*
X1394782D01*
X1396528Y340185D01*
X1397620Y339018D01*
X1398057Y336685D01*
X1397620Y334351D01*
X1396310Y332893D01*
X1394782Y332018D01*
X1389323D01*
G01X1394782D02*
X1398057Y323560D01*
G01X1407915Y331435D02*
X1414902D01*
X1414247Y333477D01*
X1413155Y334643D01*
X1411627Y335226D01*
X1410098Y334935D01*
X1408788Y334060D01*
X1407915Y332018D01*
X1407478Y330268D01*
Y328518D01*
X1407915Y326768D01*
X1409007Y325018D01*
X1410317Y323852D01*
X1411845Y323560D01*
X1413373Y324143D01*
X1414902Y325893D01*
G01X1427380Y323560D02*
Y338435D01*
X1427817Y339893D01*
X1428690Y340768D01*
X1430000Y341060D01*
X1431310Y340477D01*
X1431965Y339018D01*
G01X1429345Y334060D02*
X1424978D01*
G01X1446190Y322977D02*
X1445753Y323268D01*
Y323852D01*
X1446190Y324143D01*
X1446627Y323852D01*
Y323268D01*
X1446190Y322977D01*
G01X1476823Y323560D02*
Y341060D01*
X1482063D01*
X1483810Y340185D01*
X1485120Y338143D01*
X1485557Y335810D01*
X1485120Y333477D01*
X1484028Y331727D01*
X1482063Y330851D01*
X1476823D01*
G01X1498690Y323560D02*
Y341060D01*
G01X1520120Y323560D02*
Y335226D01*
G01Y333185D02*
X1519247Y334351D01*
X1517936Y334935D01*
X1516408Y335226D01*
X1514880Y334643D01*
X1513570Y333477D01*
X1512696Y331727D01*
X1512260Y329393D01*
X1512696Y327060D01*
X1513570Y325310D01*
X1514880Y324143D01*
X1516408Y323560D01*
X1517936Y323852D01*
X1519247Y324726D01*
X1520120Y325893D01*
G01X1529978Y323560D02*
Y335226D01*
G01Y332310D02*
X1530852Y333768D01*
X1532162Y334935D01*
X1533908Y335226D01*
X1535436Y334935D01*
X1536747Y333768D01*
X1537402Y331727D01*
Y323560D01*
G01X1547915Y331435D02*
X1554902D01*
X1554247Y333477D01*
X1553155Y334643D01*
X1551627Y335226D01*
X1550098Y334935D01*
X1548788Y334060D01*
X1547915Y332018D01*
X1547478Y330268D01*
Y328518D01*
X1547915Y326768D01*
X1549007Y325018D01*
X1550317Y323852D01*
X1551845Y323560D01*
X1553373Y324143D01*
X1554902Y325893D01*
G01X1433073Y306410D02*
Y288910D01*
X1441807D01*
G01X1450792Y303493D02*
X1452102Y305243D01*
X1453630Y306118D01*
X1455377Y306410D01*
X1457560Y305827D01*
X1459088Y304368D01*
X1459525Y302619D01*
X1459307Y300868D01*
X1458433Y299410D01*
X1454067Y296493D01*
X1452102Y294452D01*
X1450792Y291534D01*
X1450355Y288910D01*
X1459525D01*
G01X1468510Y288327D02*
X1476370Y306410D01*
G01X1485573D02*
Y288910D01*
X1494307D01*
G01X1510060D02*
Y306410D01*
X1501981Y293868D01*
X1512899D01*
G01X1668990Y300576D02*
Y288910D01*
G01Y305243D02*
X1668553Y305535D01*
Y306118D01*
X1668990Y306410D01*
X1669427Y306118D01*
Y305535D01*
X1668990Y305243D01*
G01X1683215Y290951D02*
X1684307Y289785D01*
X1685835Y288910D01*
X1687145D01*
X1688455Y289493D01*
X1689328Y290368D01*
X1689765Y291534D01*
X1689547Y293285D01*
X1688673Y294160D01*
X1684743Y295910D01*
X1683870Y297952D01*
X1684307Y299410D01*
X1685180Y300285D01*
X1686490Y300576D01*
X1687800Y300285D01*
X1689110Y299410D01*
G01X1716468Y288910D02*
Y306410D01*
X1726512Y288910D01*
Y306410D01*
G01X1738990Y288910D02*
X1737243Y289202D01*
X1735715Y290368D01*
X1734405Y292118D01*
X1733531Y294160D01*
X1733095Y296493D01*
Y298827D01*
X1733531Y301160D01*
X1734405Y303202D01*
X1735715Y304951D01*
X1737243Y306118D01*
X1738990Y306410D01*
X1740736Y306118D01*
X1742265Y304951D01*
X1743575Y303202D01*
X1744449Y301160D01*
X1744885Y298827D01*
Y296493D01*
X1744449Y294160D01*
X1743575Y292118D01*
X1742265Y290368D01*
X1740736Y289202D01*
X1738990Y288910D01*
G01X1756490Y306410D02*
Y288910D01*
G01X1751468Y306410D02*
X1761512D01*
G01X1787778Y300576D02*
Y292410D01*
X1788652Y290368D01*
X1789962Y289202D01*
X1791490Y288910D01*
X1793018Y289202D01*
X1794328Y290368D01*
X1795202Y292410D01*
G01Y288910D02*
Y300576D01*
G01X1805715Y290951D02*
X1806807Y289785D01*
X1808335Y288910D01*
X1809645D01*
X1810955Y289493D01*
X1811828Y290368D01*
X1812265Y291534D01*
X1812047Y293285D01*
X1811173Y294160D01*
X1807243Y295910D01*
X1806370Y297952D01*
X1806807Y299410D01*
X1807680Y300285D01*
X1808990Y300576D01*
X1810300Y300285D01*
X1811610Y299410D01*
G01X1823215Y296785D02*
X1830202D01*
X1829547Y298827D01*
X1828455Y299993D01*
X1826927Y300576D01*
X1825398Y300285D01*
X1824088Y299410D01*
X1823215Y297368D01*
X1822778Y295618D01*
Y293868D01*
X1823215Y292118D01*
X1824307Y290368D01*
X1825617Y289202D01*
X1827145Y288910D01*
X1828673Y289493D01*
X1830202Y291243D01*
G01X1847920Y306410D02*
Y288910D01*
G01Y291534D02*
X1847047Y290076D01*
X1845736Y289202D01*
X1844208Y288910D01*
X1842462Y289493D01*
X1841152Y290951D01*
X1840278Y292701D01*
X1840060Y294743D01*
X1840278Y296785D01*
X1841152Y298535D01*
X1842462Y299993D01*
X1844208Y300576D01*
X1845736Y300285D01*
X1846828Y299701D01*
X1847920Y298535D01*
G01X1594187Y322977D02*
X1603793Y335810D01*
G01X1598990Y338143D02*
Y320643D01*
G01X1603793Y322977D02*
X1594187Y335810D01*
G01X1592440Y329393D02*
X1605540D01*
G01X1631152D02*
X1636828D01*
G01X1664187Y323560D02*
Y341060D01*
X1668553D01*
X1670300Y340185D01*
X1671610Y339018D01*
X1672702Y337269D01*
X1673575Y335226D01*
X1673793Y332310D01*
X1673575Y329393D01*
X1672702Y327351D01*
X1671610Y325601D01*
X1670300Y324435D01*
X1668553Y323560D01*
X1664187D01*
G01X1683215Y331435D02*
X1690202D01*
X1689547Y333477D01*
X1688455Y334643D01*
X1686927Y335226D01*
X1685398Y334935D01*
X1684088Y334060D01*
X1683215Y332018D01*
X1682778Y330268D01*
Y328518D01*
X1683215Y326768D01*
X1684307Y325018D01*
X1685617Y323852D01*
X1687145Y323560D01*
X1688673Y324143D01*
X1690202Y325893D01*
G01X1700278Y323560D02*
Y335226D01*
G01Y332310D02*
X1701152Y333768D01*
X1702462Y334935D01*
X1704208Y335226D01*
X1705736Y334935D01*
X1707047Y333768D01*
X1707702Y331727D01*
Y323560D01*
G01X1721490D02*
X1720180Y323852D01*
X1718870Y325018D01*
X1717996Y327060D01*
X1717560Y329393D01*
X1717996Y331727D01*
X1718870Y333768D01*
X1720180Y334935D01*
X1721490Y335226D01*
X1722800Y334935D01*
X1724110Y333768D01*
X1724983Y331727D01*
X1725202Y329393D01*
X1724983Y327060D01*
X1724110Y325018D01*
X1722800Y323852D01*
X1721490Y323560D01*
G01X1738990Y341060D02*
Y323560D01*
G01X1735933Y335226D02*
X1742047D01*
G01X1753215Y331435D02*
X1760202D01*
X1759547Y333477D01*
X1758455Y334643D01*
X1756927Y335226D01*
X1755398Y334935D01*
X1754088Y334060D01*
X1753215Y332018D01*
X1752778Y330268D01*
Y328518D01*
X1753215Y326768D01*
X1754307Y325018D01*
X1755617Y323852D01*
X1757145Y323560D01*
X1758673Y324143D01*
X1760202Y325893D01*
G01X1770715Y325601D02*
X1771807Y324435D01*
X1773335Y323560D01*
X1774645D01*
X1775955Y324143D01*
X1776828Y325018D01*
X1777265Y326184D01*
X1777047Y327935D01*
X1776173Y328810D01*
X1772243Y330560D01*
X1771370Y332602D01*
X1771807Y334060D01*
X1772680Y334935D01*
X1773990Y335226D01*
X1775300Y334935D01*
X1776610Y334060D01*
G01X1808990Y341060D02*
Y323560D01*
G01X1805933Y335226D02*
X1812047D01*
G01X1822778Y323560D02*
Y341060D01*
G01Y332602D02*
X1823870Y334060D01*
X1824962Y334935D01*
X1826708Y335226D01*
X1828018Y334935D01*
X1829547Y333768D01*
X1830202Y332018D01*
Y323560D01*
G01X1847920D02*
Y335226D01*
G01Y333185D02*
X1847047Y334351D01*
X1845736Y334935D01*
X1844208Y335226D01*
X1842680Y334643D01*
X1841370Y333477D01*
X1840496Y331727D01*
X1840060Y329393D01*
X1840496Y327060D01*
X1841370Y325310D01*
X1842680Y324143D01*
X1844208Y323560D01*
X1845736Y323852D01*
X1847047Y324726D01*
X1847920Y325893D01*
G01X1861490Y341060D02*
Y323560D01*
G01X1858433Y335226D02*
X1864547D01*
G01X1896490Y341060D02*
Y323560D01*
G01X1893433Y335226D02*
X1899547D01*
G01X1910278Y323560D02*
Y341060D01*
G01Y332602D02*
X1911370Y334060D01*
X1912462Y334935D01*
X1914208Y335226D01*
X1915518Y334935D01*
X1917047Y333768D01*
X1917702Y332018D01*
Y323560D01*
G01X1931490Y335226D02*
Y323560D01*
G01Y339893D02*
X1931053Y340185D01*
Y340768D01*
X1931490Y341060D01*
X1931927Y340768D01*
Y340185D01*
X1931490Y339893D01*
G01X1945715Y325601D02*
X1946807Y324435D01*
X1948335Y323560D01*
X1949645D01*
X1950955Y324143D01*
X1951828Y325018D01*
X1952265Y326184D01*
X1952047Y327935D01*
X1951173Y328810D01*
X1947243Y330560D01*
X1946370Y332602D01*
X1946807Y334060D01*
X1947680Y334935D01*
X1948990Y335226D01*
X1950300Y334935D01*
X1951610Y334060D01*
G01X1981370Y341060D02*
X1986610D01*
G01X1983990D02*
Y323560D01*
G01X1981370D02*
X1986610D01*
G01X1994940D02*
Y335226D01*
G01Y332018D02*
X1995595Y333477D01*
X1996687Y334643D01*
X1998215Y335226D01*
X1999743Y334643D01*
X2000835Y333477D01*
X2001490Y332018D01*
Y323560D01*
G01Y332018D02*
X2002145Y333477D01*
X2003236Y334643D01*
X2004765Y335226D01*
X2006293Y334643D01*
X2007385Y333477D01*
X2008040Y331727D01*
Y323560D01*
G01X2015060Y317727D02*
Y335226D01*
G01Y332602D02*
X2016152Y334060D01*
X2017243Y334935D01*
X2018990Y335226D01*
X2020518Y334935D01*
X2022047Y333477D01*
X2022702Y331435D01*
X2022920Y329393D01*
X2022702Y327351D01*
X2022047Y325310D01*
X2020736Y324143D01*
X2018990Y323560D01*
X2017462Y323852D01*
X2015933Y324726D01*
X2015060Y325893D01*
G01X2033215Y331435D02*
X2040202D01*
X2039547Y333477D01*
X2038455Y334643D01*
X2036927Y335226D01*
X2035398Y334935D01*
X2034088Y334060D01*
X2033215Y332018D01*
X2032778Y330268D01*
Y328518D01*
X2033215Y326768D01*
X2034307Y325018D01*
X2035617Y323852D01*
X2037145Y323560D01*
X2038673Y324143D01*
X2040202Y325893D01*
G01X2057920Y341060D02*
Y323560D01*
G01Y326184D02*
X2057047Y324726D01*
X2055736Y323852D01*
X2054208Y323560D01*
X2052462Y324143D01*
X2051152Y325601D01*
X2050278Y327351D01*
X2050060Y329393D01*
X2050278Y331435D01*
X2051152Y333185D01*
X2052462Y334643D01*
X2054208Y335226D01*
X2055736Y334935D01*
X2056828Y334351D01*
X2057920Y333185D01*
G01X2075420Y323560D02*
Y335226D01*
G01Y333185D02*
X2074547Y334351D01*
X2073236Y334935D01*
X2071708Y335226D01*
X2070180Y334643D01*
X2068870Y333477D01*
X2067996Y331727D01*
X2067560Y329393D01*
X2067996Y327060D01*
X2068870Y325310D01*
X2070180Y324143D01*
X2071708Y323560D01*
X2073236Y323852D01*
X2074547Y324726D01*
X2075420Y325893D01*
G01X2085278Y323560D02*
Y335226D01*
G01Y332310D02*
X2086152Y333768D01*
X2087462Y334935D01*
X2089208Y335226D01*
X2090736Y334935D01*
X2092047Y333768D01*
X2092702Y331727D01*
Y323560D01*
G01X2109983Y333768D02*
X2108455Y334935D01*
X2107145Y335226D01*
X2105398Y334643D01*
X2104088Y333477D01*
X2103215Y331435D01*
X2102996Y329393D01*
X2103215Y327351D01*
X2104088Y325601D01*
X2105398Y324143D01*
X2107145Y323560D01*
X2108673Y324143D01*
X2109983Y325310D01*
G01X2120715Y331435D02*
X2127702D01*
X2127047Y333477D01*
X2125955Y334643D01*
X2124427Y335226D01*
X2122898Y334935D01*
X2121588Y334060D01*
X2120715Y332018D01*
X2120278Y330268D01*
Y328518D01*
X2120715Y326768D01*
X2121807Y325018D01*
X2123117Y323852D01*
X2124645Y323560D01*
X2126173Y324143D01*
X2127702Y325893D01*
G54D12*
G01X283015Y77985D02*
X280349Y80652D01*
G01X283917Y78887D02*
X281251Y81554D01*
G01X286645Y75560D02*
G02X283015Y77985I4274J10327D01*
G01X287133Y76738D02*
G02X283917Y78887I3787J9148D01*
G01X288329Y75225D02*
G02X286645Y75560I1J4406D01*
G01X288330Y76500D02*
G02X287133Y76738I0J3131D01*
G01X283917Y78887D02*
X281251Y81554D01*
G01X283015Y77985D02*
X280349Y80652D01*
G01X287133Y76738D02*
G02X283917Y78887I3787J9148D01*
G01X286645Y75560D02*
G02X283015Y77985I4274J10327D01*
G01X288330Y76500D02*
G02X287133Y76738I0J3131D01*
G01X288329Y75225D02*
G02X286645Y75560I1J4406D01*
G01X280725Y88385D02*
Y109563D01*
G01X282000Y88385D02*
Y109563D01*
G01X281081Y86593D02*
G02X280725Y88385I4326J1791D01*
G01X282259Y87081D02*
G02X282000Y88385I3148J1303D01*
G01X281362Y85915D02*
X281081Y86593D01*
G01X282540Y86403D02*
X282259Y87081D01*
G01X283176Y83200D02*
G02X281362Y85915I5919J5918D01*
G01X284078Y84102D02*
G02X282540Y86403I5016J5017D01*
G01X284977Y81399D02*
X283176Y83200D01*
G01X285879Y82301D02*
X284078Y84102D01*
G01X287871Y79467D02*
G02X284977Y81399I3403J8231D01*
G01X288359Y80645D02*
G02X285879Y82301I2916J7053D01*
G01X282000Y88385D02*
Y109563D01*
G01X280725Y88385D02*
Y109563D01*
G01X282259Y87081D02*
G02X282000Y88385I3148J1303D01*
G01X281081Y86593D02*
G02X280725Y88385I4326J1791D01*
G01X282540Y86403D02*
X282259Y87081D01*
G01X281362Y85915D02*
X281081Y86593D01*
G01X284078Y84102D02*
G02X282540Y86403I5016J5017D01*
G01X283176Y83200D02*
G02X281362Y85915I5919J5918D01*
G01X285879Y82301D02*
X284078Y84102D01*
G01X284977Y81399D02*
X283176Y83200D01*
G01X288359Y80645D02*
G02X285879Y82301I2916J7053D01*
G01X287871Y79467D02*
G02X284977Y81399I3403J8231D01*
G01X276925Y87963D02*
Y98462D01*
G01X278200Y87963D02*
Y98462D01*
G01X277417Y85489D02*
G02X276925Y87963I5971J2473D01*
G01X278595Y85977D02*
G02X278200Y87963I4793J1986D01*
G01X277906Y84309D02*
X277417Y85489D01*
G01X279084Y84797D02*
X278595Y85977D01*
G01X280349Y80652D02*
G02X277906Y84309I7974J7971D01*
G01X281251Y81554D02*
G02X279084Y84797I7071J7071D01*
G01X278200Y87963D02*
Y98462D01*
G01X276925Y87963D02*
Y98462D01*
G01X278595Y85977D02*
G02X278200Y87963I4793J1986D01*
G01X277417Y85489D02*
G02X276925Y87963I5971J2473D01*
G01X279084Y84797D02*
X278595Y85977D01*
G01X277906Y84309D02*
X277417Y85489D01*
G01X281251Y81554D02*
G02X279084Y84797I7071J7071D01*
G01X280349Y80652D02*
G02X277906Y84309I7974J7971D01*
G01X279014Y111273D02*
X277500D01*
G01X280224Y110771D02*
G03X279014Y111273I-1211J-1209D01*
G01X281126Y111673D02*
G03X279014Y112548I-2112J-2111D01*
G01X282000Y109563D02*
G03X281126Y111673I-2984J0D01*
G01X280725Y109563D02*
G03X280224Y110771I-1709J-1D01*
G01X281126Y111673D02*
G03X279014Y112548I-2112J-2111D01*
G01X282000Y109563D02*
G03X281126Y111673I-2984J0D01*
G01X279014Y111273D02*
X277500D01*
G01X281126Y111673D02*
G03X279014Y112548I-2112J-2111D01*
G01X280224Y110771D02*
G03X279014Y111273I-1211J-1209D01*
G01X280725Y109563D02*
G03X280224Y110771I-1709J-1D01*
G01X282000Y109563D02*
G03X281126Y111673I-2984J0D01*
G01X280224Y110771D02*
G03X279014Y111273I-1211J-1209D01*
G01X280725Y109563D02*
G03X280224Y110771I-1709J-1D01*
G01X275925Y99462D02*
X275500D01*
G01X275925Y100737D02*
X275500D01*
G01X276925Y98462D02*
G03X275925Y99462I-1000J0D01*
G01X278200Y98462D02*
G03X275925Y100737I-2275J0D01*
G01D02*
X275500D01*
G01X275925Y99462D02*
X275500D01*
G01X278200Y98462D02*
G03X275925Y100737I-2275J0D01*
G01X276925Y98462D02*
G03X275925Y99462I-1000J0D01*
G01X279014Y112548D02*
X277500D01*
G01X279014D02*
X277500D01*
G01X308010Y156491D02*
X280350Y184151D01*
G01X308010Y156491D02*
X280350Y184151D01*
G01X280725Y193822D02*
Y218225D01*
G01X282000Y193821D02*
Y218225D01*
G01X284027Y185849D02*
G02X280725Y193822I7973J7972D01*
G01X284929Y186751D02*
G02X282001Y193822I7071J7070D01*
G01X284829Y185047D02*
X284027Y185849D01*
G01X285731Y185950D02*
X284929Y186751D01*
G01X286597Y184315D02*
G02X284829Y185047I0J2501D01*
G01X286597Y185590D02*
G02X285731Y185950I2J1225D01*
G01X300874Y184315D02*
X286597D01*
G01X300874Y185590D02*
X286597D01*
G01X278200Y191540D02*
Y207124D01*
G01X276925Y191540D02*
Y207124D01*
G01X278628Y189394D02*
G02X278200Y191540I5162J2145D01*
G01X277450Y188904D02*
G02X276925Y191540I6340J2633D01*
G01X279089Y188286D02*
X278628Y189394D01*
G01X277911Y187796D02*
X277450Y188904D01*
G01X281252Y185053D02*
G02X279089Y188286I7071J7071D01*
G01X280350Y184151D02*
G02X277911Y187796I7973J7973D01*
G01X308912Y157393D02*
X281252Y185053D01*
G01X282000Y193821D02*
Y218225D01*
G01X280725Y193822D02*
Y218225D01*
G01X284929Y186751D02*
G02X282001Y193822I7071J7070D01*
G01X284027Y185849D02*
G02X280725Y193822I7973J7972D01*
G01X285731Y185950D02*
X284929Y186751D01*
G01X284829Y185047D02*
X284027Y185849D01*
G01X286597Y185590D02*
G02X285731Y185950I2J1225D01*
G01X286597Y184315D02*
G02X284829Y185047I0J2501D01*
G01X300874Y185590D02*
X286597D01*
G01X300874Y184315D02*
X286597D01*
G01X276925Y191540D02*
Y207124D01*
G01X278200Y191540D02*
Y207124D01*
G01X277450Y188904D02*
G02X276925Y191540I6340J2633D01*
G01X278628Y189394D02*
G02X278200Y191540I5162J2145D01*
G01X277911Y187796D02*
X277450Y188904D01*
G01X279089Y188286D02*
X278628Y189394D01*
G01X280350Y184151D02*
G02X277911Y187796I7973J7973D01*
G01X281252Y185053D02*
G02X279089Y188286I7071J7071D01*
G01X308912Y157393D02*
X281252Y185053D01*
G01X275925Y209399D02*
X275500D01*
G01X275925Y208124D02*
X275500D01*
G01X278200Y207124D02*
G03X275925Y209399I-2275J0D01*
G01X276925Y207124D02*
G03X275925Y208124I-1000J0D01*
G01D02*
X275500D01*
G01X275925Y209399D02*
X275500D01*
G01X276925Y207124D02*
G03X275925Y208124I-1000J0D01*
G01X278200Y207124D02*
G03X275925Y209399I-2275J0D01*
G01X279014Y219935D02*
X277500D01*
G01X279014Y221210D02*
X277500D01*
G01X280224Y219433D02*
G03X279014Y219935I-1211J-1209D01*
G01X281126Y220335D02*
G03X279014Y221210I-2112J-2111D01*
G01X282000Y218225D02*
G03X281126Y220335I-2984J0D01*
G01X280725Y218225D02*
G03X280224Y219433I-1709J-1D01*
G01X281126Y220335D02*
G03X279014Y221210I-2112J-2111D01*
G01X282000Y218225D02*
G03X281126Y220335I-2984J0D01*
G01X279014Y221210D02*
X277500D01*
G01X279014Y219935D02*
X277500D01*
G01X281126Y220335D02*
G03X279014Y221210I-2112J-2111D01*
G01X280224Y219433D02*
G03X279014Y219935I-1211J-1209D01*
G01X280725Y218225D02*
G03X280224Y219433I-1709J-1D01*
G01X282000Y218225D02*
G03X281126Y220335I-2984J0D01*
G01X280224Y219433D02*
G03X279014Y219935I-1211J-1209D01*
G01X280725Y218225D02*
G03X280224Y219433I-1709J-1D01*
G01X289281Y79186D02*
G02X287871Y79467I2J3689D01*
G01X323000Y79186D02*
X289281D01*
G01D02*
G02X287871Y79467I2J3689D01*
G01X323000Y79186D02*
X289281D01*
G01X300464Y75225D02*
X288329D01*
G01X300464Y76500D02*
X288330D01*
G01X301330Y74866D02*
G03X300464Y75225I-867J-867D01*
G01X302232Y75768D02*
G03X300464Y76500I-1768J-1769D01*
G01X314803Y61393D02*
X301330Y74866D01*
G01X315705Y62295D02*
X302232Y75768D01*
G01X300464Y76500D02*
X288330D01*
G01X300464Y75225D02*
X288329D01*
G01X302232Y75768D02*
G03X300464Y76500I-1768J-1769D01*
G01X301330Y74866D02*
G03X300464Y75225I-867J-867D01*
G01X315705Y62295D02*
X302232Y75768D01*
G01X314803Y61393D02*
X301330Y74866D01*
G01X289282Y80461D02*
G02X288359Y80645I1J2414D01*
G01X323000Y80461D02*
X289282D01*
G01D02*
G02X288359Y80645I1J2414D01*
G01X323000Y80461D02*
X289282D01*
G01X301740Y183956D02*
G03X300874Y184315I-867J-867D01*
G01X302642Y184858D02*
G03X300874Y185590I-1768J-1769D01*
G01X315454Y170241D02*
X301740Y183956D01*
G01X316357Y171143D02*
X302642Y184858D01*
G01D02*
G03X300874Y185590I-1768J-1769D01*
G01X301740Y183956D02*
G03X300874Y184315I-867J-867D01*
G01X316357Y171143D02*
X302642Y184858D01*
G01X315454Y170241D02*
X301740Y183956D01*
G01X317473Y60288D02*
G02X314803Y61392I-2J3777D01*
G01X317473Y61563D02*
G02X315705Y62295I0J2501D01*
G01X323501Y60288D02*
X317473D01*
G01X323500Y61563D02*
X317473D01*
G01D02*
G02X315705Y62295I0J2501D01*
G01X317473Y60288D02*
G02X314803Y61392I-2J3777D01*
G01X323500Y61563D02*
X317473D01*
G01X323501Y60288D02*
X317473D01*
G01X311975Y112042D02*
Y149998D01*
G01X310700Y112042D02*
Y149999D01*
G01X312270Y110557D02*
G02X311975Y112042I3590J1485D01*
G01X311091Y110069D02*
G02X310700Y112042I4770J1970D01*
G01X312590Y109783D02*
X312270Y110557D01*
G01X311411Y109295D02*
X311091Y110069D01*
G01X314343Y107157D02*
G02X312590Y109783I5713J5712D01*
G01X313441Y106255D02*
G02X311411Y109295I6614J6615D01*
G01X321409Y100091D02*
X314343Y107157D01*
G01X320507Y99188D02*
X313441Y106255D01*
G01X310700Y112042D02*
Y149999D01*
G01X311975Y112042D02*
Y149998D01*
G01X311091Y110069D02*
G02X310700Y112042I4770J1970D01*
G01X312270Y110557D02*
G02X311975Y112042I3590J1485D01*
G01X311411Y109295D02*
X311091Y110069D01*
G01X312590Y109783D02*
X312270Y110557D01*
G01X313441Y106255D02*
G02X311411Y109295I6614J6615D01*
G01X314343Y107157D02*
G02X312590Y109783I5713J5712D01*
G01X320507Y99188D02*
X313441Y106255D01*
G01X321409Y100091D02*
X314343Y107157D01*
G01X315814Y152722D02*
Y169375D01*
G01X317089Y152722D02*
Y169375D01*
G01X316546Y150954D02*
G02X315814Y152722I1769J1768D01*
G01X317448Y151856D02*
G02X317089Y152722I867J867D01*
G01X318291Y149209D02*
X316546Y150954D01*
G01X319193Y150112D02*
X317448Y151856D01*
G01X320059Y148477D02*
G02X318291Y149209I0J2501D01*
G01X320059Y149752D02*
G02X319193Y150112I2J1225D01*
G01X323500Y148477D02*
X320059D01*
G01X323501Y149752D02*
X320059D01*
G01X311975Y149998D02*
G03X308912Y157393I-10458J0D01*
G01X310699Y149998D02*
G03X308010Y156491I-9182J1D01*
G01X317089Y152722D02*
Y169375D01*
G01X315814Y152722D02*
Y169375D01*
G01X317448Y151856D02*
G02X317089Y152722I867J867D01*
G01X316546Y150954D02*
G02X315814Y152722I1769J1768D01*
G01X319193Y150112D02*
X317448Y151856D01*
G01X318291Y149209D02*
X316546Y150954D01*
G01X320059Y149752D02*
G02X319193Y150112I2J1225D01*
G01X320059Y148477D02*
G02X318291Y149209I0J2501D01*
G01X323501Y149752D02*
X320059D01*
G01X323500Y148477D02*
X320059D01*
G01X310699Y149998D02*
G03X308010Y156491I-9182J1D01*
G01X311975Y149998D02*
G03X308912Y157393I-10458J0D01*
G01X315814Y169375D02*
G03X315454Y170241I-1225J-2D01*
G01X317089Y169375D02*
G03X316357Y171143I-2501J0D01*
G01X317089Y169375D02*
G03X316357Y171143I-2501J0D01*
G01X315814Y169375D02*
G03X315454Y170241I-1225J-2D01*
G01X323177Y99359D02*
G02X321409Y100091I0J2501D01*
G01X323177Y98084D02*
G02X320507Y99188I-2J3777D01*
G01X323500Y99359D02*
X323177D01*
G01X323500Y98084D02*
X323177D01*
G01D02*
G02X320507Y99188I-2J3777D01*
G01X323177Y99359D02*
G02X321409Y100091I0J2501D01*
G01X323500Y98084D02*
X323177D01*
G01X323500Y99359D02*
X323177D01*
M02*
